#ISCELL
  mstr_misc dns *
  *
#ISCELL
  pure_quanta quanta_title_block_c *
  *
#CELL
  pure_quanta sn74auc2g66dctr *
  page151_i1
#CELL
  pure_quanta q_res *
  page151_i10
#CELL
  pure_quanta q_res *
  page151_i11
#ISCELL
  pure_quanta_power universal_power *
  page151_i12
#ISCELL
  pure_quanta_power gnd *
  page151_i13
#ISCELL
  pure_quanta_power gnd *
  page151_i14
#CELL
  pure_quanta q_cap *
  page151_i15
#ISCELL
  pure_quanta_power universal_power *
  page151_i16
#CELL
  pure_quanta sn74auc2g66dctr *
  page151_i17
#ISCELL
  standard offpage *
  page151_i18
#ISCELL
  pure_quanta_power gnd *
  page151_i19
#CELL
  pure_quanta q_res *
  page151_i2
#ISCELL
  pure_quanta_power universal_power *
  page151_i20
#ISCELL
  pure_quanta_power gnd *
  page151_i21
#CELL
  pure_quanta q_cap *
  page151_i22
#CELL
  pure_quanta sn74auc2g66dctr *
  page151_i23
#CELL
  pure_quanta q_res *
  page151_i25
#ISCELL
  pure_quanta_power universal_power *
  page151_i26
#CELL
  pure_quanta q_res *
  page151_i27
#ISCELL
  pure_quanta_power universal_power *
  page151_i28
#ISCELL
  pure_quanta_power gnd *
  page151_i29
#ISCELL
  pure_quanta_power gnd *
  page151_i3
#ISCELL
  standard offpage *
  page151_i30
#CELL
  pure_quanta sn74auc2g66dctr *
  page151_i31
#ISCELL
  standard offpage *
  page151_i32
#ISCELL
  standard offpage *
  page151_i33
#CELL
  pure_quanta q_res *
  page151_i34
#ISCELL
  pure_quanta_power universal_power *
  page151_i35
#CELL
  pure_quanta q_cap *
  page151_i36
#ISCELL
  pure_quanta_power gnd *
  page151_i37
#ISCELL
  pure_quanta_power gnd *
  page151_i38
#ISCELL
  pure_quanta_power gnd *
  page151_i39
#CELL
  pure_quanta q_cap *
  page151_i4
#ISCELL
  pure_quanta_power gnd *
  page151_i40
#ISCELL
  standard offpage *
  page151_i41
#CELL
  pure_quanta q_cap *
  page151_i42
#ISCELL
  pure_quanta_power gnd *
  page151_i43
#ISCELL
  pure_quanta_power universal_power *
  page151_i44
#CELL
  pure_quanta mosfet_n *
  page151_i45
#CELL
  pure_quanta mosfet_n *
  page151_i46
#ISCELL
  standard offpage *
  page151_i47
#ISCELL
  standard offpage *
  page151_i5
#ISCELL
  standard offpage *
  page151_i6
#ISCELL
  pure_quanta_power universal_power *
  page151_i9
